(kicad_pcb
	(version 20260206)
	(generator "pcbnew")
	(generator_version "10.0")
	(general
		(thickness 1.6)
		(legacy_teardrops no)
	)
	(paper "A4")
	(title_block
		(title "01162023_DA0F0TEBIF0_F0T_Expander_BD_F_brd_V02_OCP.brd")
		(comment 1 "Grand Teton / footprint 4451 of 9728 (PEX3), pads 1768-1882 of 2397")
	)
	(layers
		(0 "F.Cu" signal "TOP")
		(4 "In1.Cu" signal "GND")
		(6 "In2.Cu" signal "VCC")
		(8 "In3.Cu" signal "VCC1")
		(10 "In4.Cu" signal "GND1")
		(12 "In5.Cu" signal "IN1")
		(14 "In6.Cu" signal "GND2")
		(16 "In7.Cu" signal "IN2")
		(18 "In8.Cu" signal "GND3")
		(20 "In9.Cu" signal "IN3")
		(22 "In10.Cu" signal "GND4")
		(24 "In11.Cu" signal "IN4")
		(26 "In12.Cu" signal "GND5")
		(28 "In13.Cu" signal "IN5")
		(30 "In14.Cu" signal "GND6")
		(32 "In15.Cu" signal "IN6")
		(34 "In16.Cu" signal "GND7")
		(2 "B.Cu" signal "BOTTOM")
		(9 "F.Adhes" user "F.Adhesive")
		(11 "B.Adhes" user "B.Adhesive")
		(13 "F.Paste" user "Package Geometry/Pastemask Top")
		(15 "B.Paste" user "Package Geometry/Pastemask Bottom")
		(5 "F.SilkS" user "Ref Des/Silkscreen Top")
		(7 "B.SilkS" user "Ref Des/Silkscreen Bottom")
		(1 "F.Mask" user "Board Geometry/Soldermask Top")
		(3 "B.Mask" user "Board Geometry/Soldermask Bottom")
		(17 "Dwgs.User" user "User.Drawings")
		(19 "Cmts.User" user "User.Comments")
		(21 "Eco1.User" user "User.Eco1")
		(23 "Eco2.User" user "User.Eco2")
		(25 "Edge.Cuts" user "Board Geometry/Outline")
		(27 "Margin" user)
		(31 "F.CrtYd" user "Package Geometry/Place Bound Top")
		(29 "B.CrtYd" user "Package Geometry/Place Bound Bottom")
		(35 "F.Fab" user "Ref Des/Assembly Top")
		(33 "B.Fab" user "Ref Des/Assembly Bottom")
	)
	(footprint ""
		(layer "F.Cu")
		(at 407.949908 -295.89984)
		(property "Reference" "PEX3"
			(at -3.358642 35.5727 0)
			(unlocked yes)
			(layer "F.SilkS")
			(effects
				(font
					(size 2.032 1.524)
					(thickness 0.1524)
				)
				(justify left)
			)
		)
		(property "Value" ""
			(at 0 0 0)
			(layer "F.Fab")
			(effects
				(font
					(size 1.27 1.27)
				)
			)
		)
		(duplicate_pad_numbers_are_jumpers no)
		(pad "H8" smd circle
			(at -16.150082 -16.150082)
			(size 0.4572 0.4572)
			(layers "F.Cu" "F.Mask" "F.Paste")
			(net "P5E_PEX3_STN6_TX_DN<111>")
		)
		(pad "H9" smd circle
			(at -15.200122 -16.150082)
			(size 0.4572 0.4572)
			(layers "F.Cu" "F.Mask" "F.Paste")
			(net "GND")
		)
		(pad "H10" smd circle
			(at -14.249908 -16.150082)
			(size 0.4572 0.4572)
			(layers "F.Cu" "F.Mask" "F.Paste")
			(net "P5E_PEX3_STN6_TX_DN<109>")
		)
		(pad "H11" smd circle
			(at -13.299948 -16.150082)
			(size 0.4572 0.4572)
			(layers "F.Cu" "F.Mask" "F.Paste")
			(net "GND")
		)
		(pad "H12" smd circle
			(at -12.349988 -16.150082)
			(size 0.4572 0.4572)
			(layers "F.Cu" "F.Mask" "F.Paste")
			(net "P5E_PEX3_STN6_TX_DN<107>")
		)
		(pad "H13" smd circle
			(at -11.400028 -16.150082)
			(size 0.4572 0.4572)
			(layers "F.Cu" "F.Mask" "F.Paste")
			(net "GND")
		)
		(pad "H14" smd circle
			(at -10.450068 -16.150082)
			(size 0.4572 0.4572)
			(layers "F.Cu" "F.Mask" "F.Paste")
			(net "P5E_PEX3_STN6_TX_DN<105>")
		)
		(pad "H15" smd circle
			(at -9.500108 -16.150082)
			(size 0.4572 0.4572)
			(layers "F.Cu" "F.Mask" "F.Paste")
			(net "GND")
		)
		(pad "H16" smd circle
			(at -8.549894 -16.150082)
			(size 0.4572 0.4572)
			(layers "F.Cu" "F.Mask" "F.Paste")
			(net "P5E_PEX3_STN6_TX_DN<103>")
		)
		(pad "H17" smd circle
			(at -7.599934 -16.150082)
			(size 0.4572 0.4572)
			(layers "F.Cu" "F.Mask" "F.Paste")
			(net "GND")
		)
		(pad "H18" smd circle
			(at -6.649974 -16.150082)
			(size 0.4572 0.4572)
			(layers "F.Cu" "F.Mask" "F.Paste")
			(net "P5E_PEX3_STN6_TX_DN<101>")
		)
		(pad "H19" smd circle
			(at -5.700014 -16.150082)
			(size 0.4572 0.4572)
			(layers "F.Cu" "F.Mask" "F.Paste")
			(net "GND")
		)
		(pad "H20" smd circle
			(at -4.750054 -16.150082)
			(size 0.4572 0.4572)
			(layers "F.Cu" "F.Mask" "F.Paste")
			(net "P5E_PEX3_STN6_TX_DN<99>")
		)
		(pad "H21" smd circle
			(at -3.800094 -16.150082)
			(size 0.4572 0.4572)
			(layers "F.Cu" "F.Mask" "F.Paste")
			(net "GND")
		)
		(pad "H22" smd circle
			(at -2.84988 -16.150082)
			(size 0.4572 0.4572)
			(layers "F.Cu" "F.Mask" "F.Paste")
			(net "P5E_PEX3_STN6_TX_DN<97>")
		)
		(pad "H23" smd circle
			(at -1.89992 -16.150082)
			(size 0.4572 0.4572)
			(layers "F.Cu" "F.Mask" "F.Paste")
			(net "GND")
		)
		(pad "H24" smd circle
			(at -0.94996 -16.150082)
			(size 0.4572 0.4572)
			(layers "F.Cu" "F.Mask" "F.Paste")
			(net "P5E_PEX3_STN5_TX_DN<80>")
		)
		(pad "H25" smd circle
			(at 0 -16.150082)
			(size 0.4572 0.4572)
			(layers "F.Cu" "F.Mask" "F.Paste")
			(net "GND")
		)
		(pad "H26" smd circle
			(at 0.94996 -16.150082)
			(size 0.4572 0.4572)
			(layers "F.Cu" "F.Mask" "F.Paste")
			(net "P5E_PEX3_STN5_TX_DN<82>")
		)
		(pad "H27" smd circle
			(at 1.89992 -16.150082)
			(size 0.4572 0.4572)
			(layers "F.Cu" "F.Mask" "F.Paste")
			(net "GND")
		)
		(pad "H28" smd circle
			(at 2.84988 -16.150082)
			(size 0.4572 0.4572)
			(layers "F.Cu" "F.Mask" "F.Paste")
			(net "P5E_PEX3_STN5_TX_DN<84>")
		)
		(pad "H29" smd circle
			(at 3.800094 -16.150082)
			(size 0.4572 0.4572)
			(layers "F.Cu" "F.Mask" "F.Paste")
			(net "GND")
		)
		(pad "H30" smd circle
			(at 4.750054 -16.150082)
			(size 0.4572 0.4572)
			(layers "F.Cu" "F.Mask" "F.Paste")
			(net "P5E_PEX3_STN5_TX_DN<86>")
		)
		(pad "H31" smd circle
			(at 5.700014 -16.150082)
			(size 0.4572 0.4572)
			(layers "F.Cu" "F.Mask" "F.Paste")
			(net "GND")
		)
		(pad "H32" smd circle
			(at 6.649974 -16.150082)
			(size 0.4572 0.4572)
			(layers "F.Cu" "F.Mask" "F.Paste")
			(net "P5E_PEX3_STN5_TX_DN<88>")
		)
		(pad "H33" smd circle
			(at 7.599934 -16.150082)
			(size 0.4572 0.4572)
			(layers "F.Cu" "F.Mask" "F.Paste")
			(net "GND")
		)
		(pad "H34" smd circle
			(at 8.549894 -16.150082)
			(size 0.4572 0.4572)
			(layers "F.Cu" "F.Mask" "F.Paste")
			(net "P5E_PEX3_STN5_TX_DN<90>")
		)
		(pad "H35" smd circle
			(at 9.500108 -16.150082)
			(size 0.4572 0.4572)
			(layers "F.Cu" "F.Mask" "F.Paste")
			(net "GND")
		)
		(pad "H36" smd circle
			(at 10.450068 -16.150082)
			(size 0.4572 0.4572)
			(layers "F.Cu" "F.Mask" "F.Paste")
			(net "P5E_PEX3_STN5_TX_DN<92>")
		)
		(pad "H37" smd circle
			(at 11.400028 -16.150082)
			(size 0.4572 0.4572)
			(layers "F.Cu" "F.Mask" "F.Paste")
			(net "GND")
		)
		(pad "H38" smd circle
			(at 12.349988 -16.150082)
			(size 0.4572 0.4572)
			(layers "F.Cu" "F.Mask" "F.Paste")
			(net "P5E_PEX3_STN5_TX_DN<94>")
		)
		(pad "H39" smd circle
			(at 13.299948 -16.150082)
			(size 0.4572 0.4572)
			(layers "F.Cu" "F.Mask" "F.Paste")
			(net "GND")
		)
		(pad "H40" smd circle
			(at 14.249908 -16.150082)
			(size 0.4572 0.4572)
			(layers "F.Cu" "F.Mask" "F.Paste")
			(net "P5E_PEX3_STN4_TX_DN<79>")
		)
		(pad "H41" smd circle
			(at 15.200122 -16.150082)
			(size 0.4572 0.4572)
			(layers "F.Cu" "F.Mask" "F.Paste")
			(net "GND")
		)
		(pad "H42" smd circle
			(at 16.150082 -16.150082)
			(size 0.4572 0.4572)
			(layers "F.Cu" "F.Mask" "F.Paste")
			(net "P5E_PEX3_STN4_TX_DN<77>")
		)
		(pad "H43" smd circle
			(at 17.100042 -16.150082)
			(size 0.4572 0.4572)
			(layers "F.Cu" "F.Mask" "F.Paste")
			(net "GND")
		)
		(pad "H44" smd circle
			(at 18.050002 -16.150082)
			(size 0.4572 0.4572)
			(layers "F.Cu" "F.Mask" "F.Paste")
			(net "P5E_PEX3_STN4_TX_DN<75>")
		)
		(pad "H45" smd circle
			(at 18.999962 -16.150082)
			(size 0.4572 0.4572)
			(layers "F.Cu" "F.Mask" "F.Paste")
			(net "GND")
		)
		(pad "H46" smd circle
			(at 19.949922 -16.150082)
			(size 0.4572 0.4572)
			(layers "F.Cu" "F.Mask" "F.Paste")
			(net "P5E_PEX3_STN4_TX_DN<73>")
		)
		(pad "H47" smd circle
			(at 20.899882 -16.150082)
			(size 0.4572 0.4572)
			(layers "F.Cu" "F.Mask" "F.Paste")
			(net "GND")
		)
		(pad "H48" smd circle
			(at 21.850096 -16.150082)
			(size 0.4572 0.4572)
			(layers "F.Cu" "F.Mask" "F.Paste")
			(net "P5E_PEX3_STN4_TX_DP<70>")
		)
		(pad "H49" smd circle
			(at 22.800056 -16.150082)
			(size 0.4572 0.4572)
			(layers "F.Cu" "F.Mask" "F.Paste")
			(net "P5E_PEX3_STN4_TX_DN<70>")
		)
		(pad "J1" smd circle
			(at -22.800056 -15.200122)
			(size 0.4572 0.4572)
			(layers "F.Cu" "F.Mask" "F.Paste")
			(net "GND")
		)
		(pad "J2" smd circle
			(at -21.850096 -15.200122)
			(size 0.4572 0.4572)
			(layers "F.Cu" "F.Mask" "F.Paste")
			(net "GND")
		)
		(pad "J3" smd circle
			(at -20.899882 -15.200122)
			(size 0.4572 0.4572)
			(layers "F.Cu" "F.Mask" "F.Paste")
			(net "GND")
		)
		(pad "J4" smd circle
			(at -19.949922 -15.200122)
			(size 0.4572 0.4572)
			(layers "F.Cu" "F.Mask" "F.Paste")
			(net "P5E_PEX3_STN7_TX_DP<124>")
		)
		(pad "J5" smd circle
			(at -18.999962 -15.200122)
			(size 0.4572 0.4572)
			(layers "F.Cu" "F.Mask" "F.Paste")
			(net "GND")
		)
		(pad "J6" smd circle
			(at -18.050002 -15.200122)
			(size 0.4572 0.4572)
			(layers "F.Cu" "F.Mask" "F.Paste")
			(net "P5E_PEX3_STN7_TX_DP<126>")
		)
		(pad "J7" smd circle
			(at -17.100042 -15.200122)
			(size 0.4572 0.4572)
			(layers "F.Cu" "F.Mask" "F.Paste")
			(net "GND")
		)
		(pad "J8" smd circle
			(at -16.150082 -15.200122)
			(size 0.4572 0.4572)
			(layers "F.Cu" "F.Mask" "F.Paste")
			(net "P5E_PEX3_STN6_TX_DP<111>")
		)
		(pad "J9" smd circle
			(at -15.200122 -15.200122)
			(size 0.4572 0.4572)
			(layers "F.Cu" "F.Mask" "F.Paste")
			(net "GND")
		)
		(pad "J10" smd circle
			(at -14.249908 -15.200122)
			(size 0.4572 0.4572)
			(layers "F.Cu" "F.Mask" "F.Paste")
			(net "P5E_PEX3_STN6_TX_DP<109>")
		)
		(pad "J11" smd circle
			(at -13.299948 -15.200122)
			(size 0.4572 0.4572)
			(layers "F.Cu" "F.Mask" "F.Paste")
			(net "GND")
		)
		(pad "J12" smd circle
			(at -12.349988 -15.200122)
			(size 0.4572 0.4572)
			(layers "F.Cu" "F.Mask" "F.Paste")
			(net "P5E_PEX3_STN6_TX_DP<107>")
		)
		(pad "J13" smd circle
			(at -11.400028 -15.200122)
			(size 0.4572 0.4572)
			(layers "F.Cu" "F.Mask" "F.Paste")
			(net "GND")
		)
		(pad "J14" smd circle
			(at -10.450068 -15.200122)
			(size 0.4572 0.4572)
			(layers "F.Cu" "F.Mask" "F.Paste")
			(net "P5E_PEX3_STN6_TX_DP<105>")
		)
		(pad "J15" smd circle
			(at -9.500108 -15.200122)
			(size 0.4572 0.4572)
			(layers "F.Cu" "F.Mask" "F.Paste")
			(net "GND")
		)
		(pad "J16" smd circle
			(at -8.549894 -15.200122)
			(size 0.4572 0.4572)
			(layers "F.Cu" "F.Mask" "F.Paste")
			(net "P5E_PEX3_STN6_TX_DP<103>")
		)
		(pad "J17" smd circle
			(at -7.599934 -15.200122)
			(size 0.4572 0.4572)
			(layers "F.Cu" "F.Mask" "F.Paste")
			(net "GND")
		)
		(pad "J18" smd circle
			(at -6.649974 -15.200122)
			(size 0.4572 0.4572)
			(layers "F.Cu" "F.Mask" "F.Paste")
			(net "P5E_PEX3_STN6_TX_DP<101>")
		)
		(pad "J19" smd circle
			(at -5.700014 -15.200122)
			(size 0.4572 0.4572)
			(layers "F.Cu" "F.Mask" "F.Paste")
			(net "GND")
		)
		(pad "J20" smd circle
			(at -4.750054 -15.200122)
			(size 0.4572 0.4572)
			(layers "F.Cu" "F.Mask" "F.Paste")
			(net "P5E_PEX3_STN6_TX_DP<99>")
		)
		(pad "J21" smd circle
			(at -3.800094 -15.200122)
			(size 0.4572 0.4572)
			(layers "F.Cu" "F.Mask" "F.Paste")
			(net "GND")
		)
		(pad "J22" smd circle
			(at -2.84988 -15.200122)
			(size 0.4572 0.4572)
			(layers "F.Cu" "F.Mask" "F.Paste")
			(net "P5E_PEX3_STN6_TX_DP<97>")
		)
		(pad "J23" smd circle
			(at -1.89992 -15.200122)
			(size 0.4572 0.4572)
			(layers "F.Cu" "F.Mask" "F.Paste")
			(net "GND")
		)
		(pad "J24" smd circle
			(at -0.94996 -15.200122)
			(size 0.4572 0.4572)
			(layers "F.Cu" "F.Mask" "F.Paste")
			(net "P5E_PEX3_STN5_TX_DP<80>")
		)
		(pad "J25" smd circle
			(at 0 -15.200122)
			(size 0.4572 0.4572)
			(layers "F.Cu" "F.Mask" "F.Paste")
			(net "GND")
		)
		(pad "J26" smd circle
			(at 0.94996 -15.200122)
			(size 0.4572 0.4572)
			(layers "F.Cu" "F.Mask" "F.Paste")
			(net "P5E_PEX3_STN5_TX_DP<82>")
		)
		(pad "J27" smd circle
			(at 1.89992 -15.200122)
			(size 0.4572 0.4572)
			(layers "F.Cu" "F.Mask" "F.Paste")
			(net "GND")
		)
		(pad "J28" smd circle
			(at 2.84988 -15.200122)
			(size 0.4572 0.4572)
			(layers "F.Cu" "F.Mask" "F.Paste")
			(net "P5E_PEX3_STN5_TX_DP<84>")
		)
		(pad "J29" smd circle
			(at 3.800094 -15.200122)
			(size 0.4572 0.4572)
			(layers "F.Cu" "F.Mask" "F.Paste")
			(net "GND")
		)
		(pad "J30" smd circle
			(at 4.750054 -15.200122)
			(size 0.4572 0.4572)
			(layers "F.Cu" "F.Mask" "F.Paste")
			(net "P5E_PEX3_STN5_TX_DP<86>")
		)
		(pad "J31" smd circle
			(at 5.700014 -15.200122)
			(size 0.4572 0.4572)
			(layers "F.Cu" "F.Mask" "F.Paste")
			(net "GND")
		)
		(pad "J32" smd circle
			(at 6.649974 -15.200122)
			(size 0.4572 0.4572)
			(layers "F.Cu" "F.Mask" "F.Paste")
			(net "P5E_PEX3_STN5_TX_DP<88>")
		)
		(pad "J33" smd circle
			(at 7.599934 -15.200122)
			(size 0.4572 0.4572)
			(layers "F.Cu" "F.Mask" "F.Paste")
			(net "GND")
		)
		(pad "J34" smd circle
			(at 8.549894 -15.200122)
			(size 0.4572 0.4572)
			(layers "F.Cu" "F.Mask" "F.Paste")
			(net "P5E_PEX3_STN5_TX_DP<90>")
		)
		(pad "J35" smd circle
			(at 9.500108 -15.200122)
			(size 0.4572 0.4572)
			(layers "F.Cu" "F.Mask" "F.Paste")
			(net "GND")
		)
		(pad "J36" smd circle
			(at 10.450068 -15.200122)
			(size 0.4572 0.4572)
			(layers "F.Cu" "F.Mask" "F.Paste")
			(net "P5E_PEX3_STN5_TX_DP<92>")
		)
		(pad "J37" smd circle
			(at 11.400028 -15.200122)
			(size 0.4572 0.4572)
			(layers "F.Cu" "F.Mask" "F.Paste")
			(net "GND")
		)
		(pad "J38" smd circle
			(at 12.349988 -15.200122)
			(size 0.4572 0.4572)
			(layers "F.Cu" "F.Mask" "F.Paste")
			(net "P5E_PEX3_STN5_TX_DP<94>")
		)
		(pad "J39" smd circle
			(at 13.299948 -15.200122)
			(size 0.4572 0.4572)
			(layers "F.Cu" "F.Mask" "F.Paste")
			(net "GND")
		)
		(pad "J40" smd circle
			(at 14.249908 -15.200122)
			(size 0.4572 0.4572)
			(layers "F.Cu" "F.Mask" "F.Paste")
			(net "P5E_PEX3_STN4_TX_DP<79>")
		)
		(pad "J41" smd circle
			(at 15.200122 -15.200122)
			(size 0.4572 0.4572)
			(layers "F.Cu" "F.Mask" "F.Paste")
			(net "GND")
		)
		(pad "J42" smd circle
			(at 16.150082 -15.200122)
			(size 0.4572 0.4572)
			(layers "F.Cu" "F.Mask" "F.Paste")
			(net "P5E_PEX3_STN4_TX_DP<77>")
		)
		(pad "J43" smd circle
			(at 17.100042 -15.200122)
			(size 0.4572 0.4572)
			(layers "F.Cu" "F.Mask" "F.Paste")
			(net "GND")
		)
		(pad "J44" smd circle
			(at 18.050002 -15.200122)
			(size 0.4572 0.4572)
			(layers "F.Cu" "F.Mask" "F.Paste")
			(net "P5E_PEX3_STN4_TX_DP<75>")
		)
		(pad "J45" smd circle
			(at 18.999962 -15.200122)
			(size 0.4572 0.4572)
			(layers "F.Cu" "F.Mask" "F.Paste")
			(net "GND")
		)
		(pad "J46" smd circle
			(at 19.949922 -15.200122)
			(size 0.4572 0.4572)
			(layers "F.Cu" "F.Mask" "F.Paste")
			(net "P5E_PEX3_STN4_TX_DP<73>")
		)
		(pad "J47" smd circle
			(at 20.899882 -15.200122)
			(size 0.4572 0.4572)
			(layers "F.Cu" "F.Mask" "F.Paste")
			(net "GND")
		)
		(pad "J48" smd circle
			(at 21.850096 -15.200122)
			(size 0.4572 0.4572)
			(layers "F.Cu" "F.Mask" "F.Paste")
			(net "GND")
		)
		(pad "J49" smd circle
			(at 22.800056 -15.200122)
			(size 0.4572 0.4572)
			(layers "F.Cu" "F.Mask" "F.Paste")
			(net "GND")
		)
		(pad "K1" smd circle
			(at -22.800056 -14.249908)
			(size 0.4572 0.4572)
			(layers "F.Cu" "F.Mask" "F.Paste")
			(net "P5E_PEX3_STN7_RX_DN<121>")
		)
		(pad "K2" smd circle
			(at -21.850096 -14.249908)
			(size 0.4572 0.4572)
			(layers "F.Cu" "F.Mask" "F.Paste")
			(net "P5E_PEX3_STN7_RX_DP<121>")
		)
		(pad "K3" smd circle
			(at -20.899882 -14.249908)
			(size 0.4572 0.4572)
			(layers "F.Cu" "F.Mask" "F.Paste")
			(net "GND")
		)
		(pad "K4" smd circle
			(at -19.949922 -14.249908)
			(size 0.4572 0.4572)
			(layers "F.Cu" "F.Mask" "F.Paste")
			(net "GND")
		)
		(pad "K5" smd circle
			(at -18.999962 -14.249908)
			(size 0.4572 0.4572)
			(layers "F.Cu" "F.Mask" "F.Paste")
			(net "GND")
		)
		(pad "K6" smd circle
			(at -18.050002 -14.249908)
			(size 0.4572 0.4572)
			(layers "F.Cu" "F.Mask" "F.Paste")
			(net "GND")
		)
		(pad "K7" smd circle
			(at -17.100042 -14.249908)
			(size 0.4572 0.4572)
			(layers "F.Cu" "F.Mask" "F.Paste")
			(net "GND")
		)
		(pad "K8" smd circle
			(at -16.150082 -14.249908)
			(size 0.4572 0.4572)
			(layers "F.Cu" "F.Mask" "F.Paste")
			(net "GND")
		)
		(pad "K9" smd circle
			(at -15.200122 -14.249908)
			(size 0.4572 0.4572)
			(layers "F.Cu" "F.Mask" "F.Paste")
			(net "GND")
		)
		(pad "K10" smd circle
			(at -14.249908 -14.249908)
			(size 0.4572 0.4572)
			(layers "F.Cu" "F.Mask" "F.Paste")
			(net "GND")
		)
		(pad "K11" smd circle
			(at -13.299948 -14.249908)
			(size 0.4572 0.4572)
			(layers "F.Cu" "F.Mask" "F.Paste")
			(net "GND")
		)
		(pad "K12" smd circle
			(at -12.349988 -14.249908)
			(size 0.4572 0.4572)
			(layers "F.Cu" "F.Mask" "F.Paste")
			(net "GND")
		)
		(pad "K13" smd circle
			(at -11.400028 -14.249908)
			(size 0.4572 0.4572)
			(layers "F.Cu" "F.Mask" "F.Paste")
			(net "GND")
		)
		(pad "K14" smd circle
			(at -10.450068 -14.249908)
			(size 0.4572 0.4572)
			(layers "F.Cu" "F.Mask" "F.Paste")
			(net "GND")
		)
		(pad "K15" smd circle
			(at -9.500108 -14.249908)
			(size 0.4572 0.4572)
			(layers "F.Cu" "F.Mask" "F.Paste")
			(net "GND")
		)
		(pad "K16" smd circle
			(at -8.549894 -14.249908)
			(size 0.4572 0.4572)
			(layers "F.Cu" "F.Mask" "F.Paste")
			(net "GND")
		)
		(pad "K17" smd circle
			(at -7.599934 -14.249908)
			(size 0.4572 0.4572)
			(layers "F.Cu" "F.Mask" "F.Paste")
			(net "GND")
		)
		(pad "K18" smd circle
			(at -6.649974 -14.249908)
			(size 0.4572 0.4572)
			(layers "F.Cu" "F.Mask" "F.Paste")
			(net "GND")
		)
		(pad "K19" smd circle
			(at -5.700014 -14.249908)
			(size 0.4572 0.4572)
			(layers "F.Cu" "F.Mask" "F.Paste")
			(net "GND")
		)
		(pad "K20" smd circle
			(at -4.750054 -14.249908)
			(size 0.4572 0.4572)
			(layers "F.Cu" "F.Mask" "F.Paste")
			(net "GND")
		)
		(pad "K21" smd circle
			(at -3.800094 -14.249908)
			(size 0.4572 0.4572)
			(layers "F.Cu" "F.Mask" "F.Paste")
			(net "GND")
		)
		(pad "K22" smd circle
			(at -2.84988 -14.249908)
			(size 0.4572 0.4572)
			(layers "F.Cu" "F.Mask" "F.Paste")
			(net "GND")
		)
		(pad "K23" smd circle
			(at -1.89992 -14.249908)
			(size 0.4572 0.4572)
			(layers "F.Cu" "F.Mask" "F.Paste")
			(net "GND")
		)
		(pad "K24" smd circle
			(at -0.94996 -14.249908)
			(size 0.4572 0.4572)
			(layers "F.Cu" "F.Mask" "F.Paste")
			(net "GND")
		)
	)
)
